# BASEBOARD_FAB2 (Tioga Pass) — schematic netlist excerpt (pin names and nets, part order shuffled) for the footprints in the layout excerpt that follows; sources: Cadence DE-HDL packaged netlist, KiCad conversion of Wiwynn_Tioga_Pass_MB.brd

L1B2  IND-80NH-1-GP  pkg DISCRET-GC2  page 209 : S = P12V_STBY ; F = VR_FET_SW_P12V_STBY_PVCCIN_CPU1
R1G2  RES  1.00K 1% CHIP  pkg 0402  page 100 : A = PVDDQ_GHJ ; B = M_H_VREF
R1C36  RES  1.00K 1% CHIP  pkg 0402  page 156 : A = FM_CPU1_SM_WP ; B = GND

(kicad_pcb
	(version 20260206)
	(generator "pcbnew")
	(generator_version "10.0")
	(general
		(thickness 1.6)
		(legacy_teardrops no)
	)
	(paper "A4")
	(title_block
		(title "Wiwynn_Tioga_Pass_MB.brd")
		(comment 1 "Tioga Pass / footprints 1376-1378 of 4770")
	)
	(layers
		(0 "F.Cu" signal "TOP")
		(4 "In1.Cu" signal "L2GND")
		(6 "In2.Cu" signal "L3")
		(8 "In3.Cu" signal "L4GND")
		(10 "In4.Cu" signal "L5")
		(12 "In5.Cu" signal "L6GND")
		(14 "In6.Cu" signal "L7VCC")
		(16 "In7.Cu" signal "L8VCC")
		(18 "In8.Cu" signal "L9GND")
		(20 "In9.Cu" signal "L10")
		(22 "In10.Cu" signal "L11GND")
		(24 "In11.Cu" signal "L12")
		(26 "In12.Cu" signal "L13GND")
		(2 "B.Cu" signal "BOTTOM")
		(9 "F.Adhes" user "F.Adhesive")
		(11 "B.Adhes" user "B.Adhesive")
		(13 "F.Paste" user "Package Geometry/Pastemask Top")
		(15 "B.Paste" user "Package Geometry/Pastemask Bottom")
		(5 "F.SilkS" user "Ref Des/Silkscreen Top")
		(7 "B.SilkS" user "Ref Des/Silkscreen Bottom")
		(1 "F.Mask" user "Board Geometry/Soldermask Top")
		(3 "B.Mask" user "Board Geometry/Soldermask Bottom")
		(17 "Dwgs.User" user "User.Drawings")
		(19 "Cmts.User" user "User.Comments")
		(21 "Eco1.User" user "User.Eco1")
		(23 "Eco2.User" user "User.Eco2")
		(25 "Edge.Cuts" user "Board Geometry/Outline")
		(27 "Margin" user)
		(31 "F.CrtYd" user "Package Geometry/Place Bound Top")
		(29 "B.CrtYd" user "Package Geometry/Place Bound Bottom")
		(35 "F.Fab" user "Ref Des/Assembly Top")
		(33 "B.Fab" user "Ref Des/Assembly Bottom")
	)
	(footprint ""
		(layer "F.Cu")
		(at 28.575 -13.3731)
		(property "Reference" "R1G2"
			(at 0 0 0)
			(layer "F.SilkS")
			(hide yes)
			(effects
				(font
					(size 1.27 1.27)
				)
			)
		)
		(property "Value" ""
			(at 0 0 0)
			(layer "F.Fab")
			(effects
				(font
					(size 1.27 1.27)
				)
			)
		)
		(duplicate_pad_numbers_are_jumpers no)
		(fp_poly
			(pts
				(xy -0.2794 -0.1016) (xy 0.2794 -0.1016) (xy 0.2794 0.9906) (xy -0.2794 0.9906)
			)
			(stroke
				(width 0)
				(type default)
			)
			(fill no)
			(layer "F.CrtYd")
		)
		(fp_line
			(start -0.2794 -0.1016)
			(end -0.2794 0.9906)
			(stroke
				(width 0.1)
				(type default)
			)
			(layer "F.Fab")
		)
		(fp_line
			(start -0.2794 0.9906)
			(end 0.2794 0.9906)
			(stroke
				(width 0.1)
				(type default)
			)
			(layer "F.Fab")
		)
		(fp_line
			(start 0.2794 -0.1016)
			(end -0.2794 -0.1016)
			(stroke
				(width 0.1)
				(type default)
			)
			(layer "F.Fab")
		)
		(fp_line
			(start 0.2794 0.9906)
			(end 0.2794 -0.1016)
			(stroke
				(width 0.1)
				(type default)
			)
			(layer "F.Fab")
		)
		(pad "1" smd rect
			(at 0 0)
			(size 0.508 0.508)
			(layers "F.Cu" "F.Mask" "F.Paste")
			(net "PVDDQ_GHJ")
		)
		(pad "2" smd rect
			(at 0 0.889)
			(size 0.508 0.508)
			(layers "F.Cu" "F.Mask" "F.Paste")
			(net "M_H_VREF")
		)
		(zone
			(layer "F.Cu")
			(hatch none 0.5)
			(connect_pads
				(clearance 0)
			)
			(min_thickness 0.25)
			(keepout
				(tracks allowed)
				(vias not_allowed)
				(pads allowed)
				(copperpour not_allowed)
				(footprints allowed)
			)
			(placement
				(enabled no)
				(sheetname "")
			)
			(fill
				(thermal_gap 0.5)
				(thermal_bridge_width 0.5)
				(island_removal_mode 0)
			)
			(polygon
				(pts
					(xy 28.321 -13.1191) (xy 28.829 -13.1191) (xy 28.829 -12.7381) (xy 28.321 -12.7381)
				)
			)
		)
		(zone
			(layer "F.Cu")
			(hatch none 0.5)
			(connect_pads
				(clearance 0)
			)
			(min_thickness 0.25)
			(keepout
				(tracks not_allowed)
				(vias allowed)
				(pads allowed)
				(copperpour not_allowed)
				(footprints allowed)
			)
			(placement
				(enabled no)
				(sheetname "")
			)
			(fill
				(thermal_gap 0.5)
				(thermal_bridge_width 0.5)
				(island_removal_mode 0)
			)
			(polygon
				(pts
					(xy 28.321 -12.7381) (xy 28.829 -12.7381) (xy 28.829 -13.1191) (xy 28.321 -13.1191)
				)
			)
		)
	)
	(footprint ""
		(layer "F.Cu")
		(at 29.6418 -102.235 -90)
		(property "Reference" "R1C36"
			(at 0 0 270)
			(layer "F.SilkS")
			(hide yes)
			(effects
				(font
					(size 1.27 1.27)
				)
			)
		)
		(property "Value" ""
			(at 0 0 270)
			(layer "F.Fab")
			(effects
				(font
					(size 1.27 1.27)
				)
			)
		)
		(duplicate_pad_numbers_are_jumpers no)
		(fp_poly
			(pts
				(xy -0.2794 -0.1016) (xy 0.2794 -0.1016) (xy 0.2794 0.9906) (xy -0.2794 0.9906)
			)
			(stroke
				(width 0)
				(type default)
			)
			(fill no)
			(layer "F.CrtYd")
		)
		(fp_line
			(start -0.2794 0.9906)
			(end 0.2794 0.9906)
			(stroke
				(width 0.1)
				(type default)
			)
			(layer "F.Fab")
		)
		(fp_line
			(start 0.2794 0.9906)
			(end 0.2794 -0.1016)
			(stroke
				(width 0.1)
				(type default)
			)
			(layer "F.Fab")
		)
		(fp_line
			(start -0.2794 -0.1016)
			(end -0.2794 0.9906)
			(stroke
				(width 0.1)
				(type default)
			)
			(layer "F.Fab")
		)
		(fp_line
			(start 0.2794 -0.1016)
			(end -0.2794 -0.1016)
			(stroke
				(width 0.1)
				(type default)
			)
			(layer "F.Fab")
		)
		(pad "1" smd rect
			(at 0 0 270)
			(size 0.508 0.508)
			(layers "F.Cu" "F.Mask" "F.Paste")
			(net "FM_CPU1_SM_WP")
		)
		(pad "2" smd rect
			(at 0 0.889 270)
			(size 0.508 0.508)
			(layers "F.Cu" "F.Mask" "F.Paste")
			(net "GND")
		)
		(zone
			(layer "F.Cu")
			(hatch none 0.5)
			(connect_pads
				(clearance 0)
			)
			(min_thickness 0.25)
			(keepout
				(tracks not_allowed)
				(vias allowed)
				(pads allowed)
				(copperpour not_allowed)
				(footprints allowed)
			)
			(placement
				(enabled no)
				(sheetname "")
			)
			(fill
				(thermal_gap 0.5)
				(thermal_bridge_width 0.5)
				(island_removal_mode 0)
			)
			(polygon
				(pts
					(xy 29.0068 -102.489) (xy 29.0068 -101.981) (xy 29.3878 -101.981) (xy 29.3878 -102.489)
				)
			)
		)
		(zone
			(layer "F.Cu")
			(hatch none 0.5)
			(connect_pads
				(clearance 0)
			)
			(min_thickness 0.25)
			(keepout
				(tracks allowed)
				(vias not_allowed)
				(pads allowed)
				(copperpour not_allowed)
				(footprints allowed)
			)
			(placement
				(enabled no)
				(sheetname "")
			)
			(fill
				(thermal_gap 0.5)
				(thermal_bridge_width 0.5)
				(island_removal_mode 0)
			)
			(polygon
				(pts
					(xy 29.3878 -102.489) (xy 29.3878 -101.981) (xy 29.0068 -101.981) (xy 29.0068 -102.489)
				)
			)
		)
	)
	(footprint ""
		(layer "F.Cu")
		(at 26.210514 -117.35435)
		(property "Reference" "L1B2"
			(at 0 0 0)
			(layer "F.SilkS")
			(hide yes)
			(effects
				(font
					(size 1.27 1.27)
				)
			)
		)
		(property "Value" "*"
			(at 4.9784 -0.6477 0)
			(unlocked yes)
			(layer "F.Fab")
			(hide yes)
			(effects
				(font
					(size 1.27 1.016)
					(thickness 0.1524)
				)
			)
		)
		(property "Device Type" "IND-80NH-1-GP_DISCRET-GC2-IND-A"
			(at 4.9784 -2.1717 0)
			(unlocked yes)
			(layer "F.Fab")
			(hide yes)
			(effects
				(font
					(size 1.27 1.016)
					(thickness 0.1524)
				)
			)
		)
		(duplicate_pad_numbers_are_jumpers no)
		(fp_line
			(start -2.8575 -3.4544)
			(end 2.8575 -3.4544)
			(stroke
				(width 0.1524)
				(type default)
			)
			(layer "F.SilkS")
		)
		(fp_line
			(start -2.8575 3.4544)
			(end -2.8575 -3.4544)
			(stroke
				(width 0.1524)
				(type default)
			)
			(layer "F.SilkS")
		)
		(fp_line
			(start 2.8575 -3.4544)
			(end 2.8575 3.4544)
			(stroke
				(width 0.1524)
				(type default)
			)
			(layer "F.SilkS")
		)
		(fp_line
			(start 2.8575 3.4544)
			(end -2.8575 3.4544)
			(stroke
				(width 0.1524)
				(type default)
			)
			(layer "F.SilkS")
		)
		(fp_rect
			(start -2.6035 2.6035)
			(end 2.6035 -2.6035)
			(stroke
				(width 0)
				(type default)
			)
			(fill no)
			(layer "F.CrtYd")
		)
		(fp_poly
			(pts
				(xy -3.1115 3.5306) (xy -3.1115 2.6035) (xy 2.6035 2.6035) (xy 2.6035 -2.6035) (xy -2.6035 -2.6035)
				(xy -2.6035 2.5908) (xy -3.1115 2.5908) (xy -3.1115 -3.5306) (xy 3.1115 -3.5306) (xy 3.1115 3.5306)
			)
			(stroke
				(width 0)
				(type default)
			)
			(fill no)
			(layer "F.CrtYd")
		)
		(fp_rect
			(start -3.1115 3.5306)
			(end 3.1115 -3.5306)
			(stroke
				(width 0)
				(type default)
			)
			(fill no)
			(layer "F.Fab")
		)
		(pad "1" smd rect
			(at 0 -2.395982)
			(size 2.2606 1.6002)
			(layers "F.Cu" "F.Mask" "F.Paste")
			(net "P12V_STBY")
		)
		(pad "2" smd rect
			(at 0 2.395982)
			(size 2.2606 1.6002)
			(layers "F.Cu" "F.Mask" "F.Paste")
			(net "VR_FET_SW_P12V_STBY_PVCCIN_CPU1")
		)
	)
)
